(kicad_pcb
	(version 20221018)
	(generator pcbnew)
	(general
    (thickness 1.7403)
  )
	(paper "A4")
	(title_block
    (title "Data Center RDIMM DDR4 Tester")
    (date "2024-09-30")
    (rev "1.2.4")
		(comment 9 "footprints 111-114 of 690")
	)
	(layers
    (0 "F.Cu" signal)
    (1 "In1.Cu" power)
    (2 "In2.Cu" signal)
    (3 "In3.Cu" power)
    (4 "In4.Cu" power)
    (5 "In5.Cu" signal)
    (6 "In6.Cu" power)
    (7 "In7.Cu" signal)
    (8 "In8.Cu" power)
    (9 "In9.Cu" signal)
    (10 "In10.Cu" power)
    (31 "B.Cu" signal)
    (32 "B.Adhes" user "B.Adhesive")
    (33 "F.Adhes" user "F.Adhesive")
    (34 "B.Paste" user)
    (35 "F.Paste" user)
    (36 "B.SilkS" user "B.Silkscreen")
    (37 "F.SilkS" user "F.Silkscreen")
    (38 "B.Mask" user)
    (39 "F.Mask" user)
    (40 "Dwgs.User" user "User.Drawings")
    (41 "Cmts.User" user "User.Comments")
    (42 "Eco1.User" user "User.Eco1")
    (43 "Eco2.User" user "User.Eco2")
    (44 "Edge.Cuts" user)
    (45 "Margin" user)
    (46 "B.CrtYd" user "B.Courtyard")
    (47 "F.CrtYd" user "F.Courtyard")
    (48 "B.Fab" user)
    (49 "F.Fab" user)
  )
	(footprint "data-center-rdimm-ddr4-tester-footprints:FB_0603_1608Metric" (layer "F.Cu")
    (at 147.486328 94.610008 180)
    (property "Author" "Antmicro")
    (property "License" "Apache-2.0")
    (property "MPN" "BLM18PG121SN1D")
    (property "Manufacturer" "Murata")
    (property "Sheetfile" "ethernet.kicad_sch")
    (property "Sheetname" "Ethernet")
    (property "ki_description" "Ferrite Beads WE-TMSB Suppression 240Ohm 200mA ")
    (property "ki_keywords" " Multilayer Suppression Beads ")
    (attr smd)
    (fp_text reference "FB2" (at 1.886328 -1.559992 180) (layer "F.SilkS")
        (effects (font (size 0.7 0.7) (thickness 0.15)) (justify left bottom))
    )
    (fp_text value "FB_120Z_2A_0603" (at 0 1.7 180) (layer "F.Fab") hide
        (effects (font (size 0.7 0.7) (thickness 0.15)) (justify left bottom))
    )
    (fp_text user "${REFERENCE}" (at -1.653 4.6 180) (layer "F.Fab") hide
        (effects (font (size 0.7 0.7) (thickness 0.15)) (justify left bottom))
    )
    (fp_text user "Author: Antmicro" (at -1.653 3.162 180) (layer "F.Fab") hide
        (effects (font (size 0.7 0.7) (thickness 0.15)) (justify left bottom))
    )
    (fp_text user "License: Apache-2.0" (at -1.653 5.9 180) (layer "F.Fab") hide
        (effects (font (size 0.7 0.7) (thickness 0.15)) (justify left bottom))
    )
    (fp_line (start -0.196 -0.408) (end 0.193 -0.408)
      (stroke (width 0.15) (type solid)) (layer "F.SilkS"))
    (fp_line (start -0.196 0.406) (end 0.193 0.406)
      (stroke (width 0.15) (type solid)) (layer "F.SilkS"))
    (fp_rect (start -1.3 -0.6) (end 1.3 0.6)
      (stroke (width 0.05) (type solid)) (fill none) (layer "F.CrtYd"))
    (fp_line (start -0.803 0.406) (end -0.803 -0.408)
      (stroke (width 0.15) (type solid)) (layer "F.Fab"))
    (fp_line (start 0.8 -0.408) (end -0.803 -0.408)
      (stroke (width 0.15) (type solid)) (layer "F.Fab"))
    (fp_line (start 0.8 -0.408) (end 0.8 0.406)
      (stroke (width 0.15) (type solid)) (layer "F.Fab"))
    (fp_line (start 0.8 0.406) (end -0.803 0.406)
      (stroke (width 0.15) (type solid)) (layer "F.Fab"))
    (pad "1" smd roundrect (at -0.891 0 180) (size 0.762 1.09) (layers "F.Cu" "F.Paste" "F.Mask") (roundrect_rratio 0.15)
      (net 178 "/Ethernet/AVDDL_PLL") (pintype "passive"))
    (pad "2" smd roundrect (at 0.888 0 180) (size 0.762 1.09) (layers "F.Cu" "F.Paste" "F.Mask") (roundrect_rratio 0.15)
      (net 306 "1V2_SYS") (pintype "passive"))
  )
	(footprint "data-center-rdimm-ddr4-tester-footprints:R_0402_1005Metric" (layer "F.Cu")
    (at 151.586328 99.474306 90)
    (descr "Resistor SMD 0402")
    (tags "resistor SMD 0402")
    (property "Author" "Antmicro")
    (property "License" "Apache-2.0")
    (property "MPN" "CR0402-FX-1212GLF")
    (property "Manufacturer" "Bourns")
    (property "Sheetfile" "ethernet.kicad_sch")
    (property "Sheetname" "Ethernet")
    (property "Tolerance" "1%")
    (property "Val" "12k1")
    (property "ki_description" "12k1 resistor in 0402 package with 1% tolerance")
    (attr smd)
    (fp_text reference "R68" (at -1.145694 1.283672 90) (layer "F.SilkS")
        (effects (font (size 0.7 0.7) (thickness 0.15)) (justify left bottom))
    )
    (fp_text value "R_12k1_0402" (at 0 1.4 90) (layer "F.Fab") hide
        (effects (font (size 0.7 0.7) (thickness 0.15)) (justify left bottom))
    )
    (fp_text user "Author: Antmicro" (at -0.95 4.169 90) (layer "F.Fab") hide
        (effects (font (size 0.7 0.7) (thickness 0.15)) (justify left bottom))
    )
    (fp_text user "${REFERENCE}" (at -0.95 3.168 90) (layer "F.Fab") hide
        (effects (font (size 0.7 0.7) (thickness 0.15)) (justify left bottom))
    )
    (fp_text user "License: Apache-2.0" (at -0.95 5.169 90) (layer "F.Fab") hide
        (effects (font (size 0.7 0.7) (thickness 0.15)) (justify left bottom))
    )
    (fp_rect (start -0.93 -0.47) (end 0.93 0.47)
      (stroke (width 0.05) (type solid)) (fill none) (layer "F.CrtYd"))
    (fp_rect (start -0.5 -0.25) (end 0.5 0.25)
      (stroke (width 0.15) (type solid)) (fill none) (layer "F.Fab"))
    (pad "1" smd roundrect (at -0.485 0 90) (size 0.59 0.64) (layers "F.Cu" "F.Paste" "F.Mask") (roundrect_rratio 0.25)
      (net 9 "GND") (pintype "passive"))
    (pad "2" smd roundrect (at 0.485 0 90) (size 0.59 0.64) (layers "F.Cu" "F.Paste" "F.Mask") (roundrect_rratio 0.25)
      (net 652 "Net-(U6-ISET)") (pintype "passive"))
  )
	(footprint "data-center-rdimm-ddr4-tester-footprints:R_0402_1005Metric" (layer "F.Cu")
    (at 151.586328 97.474306 -90)
    (descr "Resistor SMD 0402")
    (tags "resistor SMD 0402")
    (property "Author" "Antmicro")
    (property "License" "Apache-2.0")
    (property "MPN" "CR0402-FX-1804GLF")
    (property "Manufacturer" "Bourns")
    (property "Sheetfile" "ethernet.kicad_sch")
    (property "Sheetname" "Ethernet")
    (property "Tolerance" "1%")
    (property "Val" "1M8")
    (property "ki_description" "1M8 resistor in 0402 package with 1% tolerance")
    (attr smd)
    (fp_text reference "R69" (at 1.125694 -1.313672 -90) (layer "F.SilkS")
        (effects (font (size 0.7 0.7) (thickness 0.15)) (justify left bottom))
    )
    (fp_text value "R_1M8_0402" (at 0 1.4 -90) (layer "F.Fab") hide
        (effects (font (size 0.7 0.7) (thickness 0.15)) (justify left bottom))
    )
    (fp_text user "${REFERENCE}" (at -0.95 3.168 -90) (layer "F.Fab") hide
        (effects (font (size 0.7 0.7) (thickness 0.15)) (justify left bottom))
    )
    (fp_text user "License: Apache-2.0" (at -0.95 5.169 -90) (layer "F.Fab") hide
        (effects (font (size 0.7 0.7) (thickness 0.15)) (justify left bottom))
    )
    (fp_text user "Author: Antmicro" (at -0.95 4.169 -90) (layer "F.Fab") hide
        (effects (font (size 0.7 0.7) (thickness 0.15)) (justify left bottom))
    )
    (fp_rect (start -0.93 -0.47) (end 0.93 0.47)
      (stroke (width 0.05) (type solid)) (fill none) (layer "F.CrtYd"))
    (fp_rect (start -0.5 -0.25) (end 0.5 0.25)
      (stroke (width 0.15) (type solid)) (fill none) (layer "F.Fab"))
    (pad "1" smd roundrect (at -0.485 0 270) (size 0.59 0.64) (layers "F.Cu" "F.Paste" "F.Mask") (roundrect_rratio 0.25)
      (net 5 "Net-(U6-XO)") (pintype "passive"))
    (pad "2" smd roundrect (at 0.485 0 270) (size 0.59 0.64) (layers "F.Cu" "F.Paste" "F.Mask") (roundrect_rratio 0.25)
      (net 6 "Net-(U6-XI)") (pintype "passive"))
  )
	(footprint "data-center-rdimm-ddr4-tester-footprints:Oscillator_SMD_Geyer_KX-7-4Pin_3.2x2.5mm" (layer "F.Cu")
    (at 148.686328 98.274306 180)
    (property "Author" "Antmicro")
    (property "License" "Apache-2.0")
    (property "MPN" "ABM8G-25.000MHZ-18-D2Y-T")
    (property "Manufacturer" "Abracon")
    (property "Sheetfile" "ethernet.kicad_sch")
    (property "Sheetname" "Ethernet")
    (property "Val" "25MHz")
    (property "ki_description" "25 MHz ±20ppm Crystal 18pF 60 Ohms 4-SMD, No Lead")
    (attr smd)
    (fp_text reference "Y1" (at 3.286328 0.854306) (layer "F.SilkS")
        (effects (font (size 0.7 0.7) (thickness 0.15)) (justify left bottom))
    )
    (fp_text value "Oscillator_SMD_25MHz_KX-7" (at -1.75 2.548 180) (layer "F.Fab") hide
        (effects (font (size 0.7 0.7) (thickness 0.15)) (justify left bottom))
    )
    (fp_text user "License: Apache-2.0" (at -1.75 6.5 180) (layer "F.Fab") hide
        (effects (font (size 0.7 0.7) (thickness 0.15)) (justify left bottom))
    )
    (fp_text user "${REFERENCE}" (at -1.75 3.75 180) (layer "F.Fab") hide
        (effects (font (size 0.7 0.7) (thickness 0.15)) (justify left bottom))
    )
    (fp_text user "Author: Antmicro" (at -1.75 5 180) (layer "F.Fab") hide
        (effects (font (size 0.7 0.7) (thickness 0.15)) (justify left bottom))
    )
    (fp_line (start -1.6 0.3) (end -1.6 -0.2)
      (stroke (width 0.15) (type solid)) (layer "F.SilkS"))
    (fp_line (start -0.35 -1.25) (end 0.45 -1.25)
      (stroke (width 0.15) (type solid)) (layer "F.SilkS"))
    (fp_line (start -0.35 1.25) (end 0.45 1.25)
      (stroke (width 0.15) (type solid)) (layer "F.SilkS"))
    (fp_line (start 1.6 0.3) (end 1.6 -0.2)
      (stroke (width 0.15) (type solid)) (layer "F.SilkS"))
    (fp_circle (center -1.75 1.5) (end -1.7 1.5)
      (stroke (width 0.15) (type solid)) (fill none) (layer "F.SilkS"))
    (fp_rect (start -1.907 -1.55) (end 2.006 1.649)
      (stroke (width 0.05) (type solid)) (fill none) (layer "F.CrtYd"))
    (pad "1" smd roundrect (at -1.101 0.949 180) (size 1.3 1.1) (layers "F.Cu" "F.Paste" "F.Mask") (roundrect_rratio 0)
      (chamfer_ratio 0.2) (chamfer bottom_left)
      (net 5 "Net-(U6-XO)") (pintype "passive"))
    (pad "2" smd rect (at 1.199 0.949 180) (size 1.3 1.1) (layers "F.Cu" "F.Paste" "F.Mask")
      (net 9 "GND") (pinfunction "SH") (pintype "passive"))
    (pad "3" smd rect (at 1.199 -0.85 180) (size 1.3 1.1) (layers "F.Cu" "F.Paste" "F.Mask")
      (net 6 "Net-(U6-XI)") (pintype "passive"))
    (pad "4" smd rect (at -1.101 -0.85 180) (size 1.3 1.1) (layers "F.Cu" "F.Paste" "F.Mask")
      (net 9 "GND") (pinfunction "SH") (pintype "passive"))
  )
)
